(kicad_pcb
	(version 20240108)
	(generator "pcbnew")
	(generator_version "8.0")
	(general
		(thickness 1.62)
		(legacy_teardrops no)
	)
	(paper "A4")
	(title_block
		(title "Jetson Orin Baseboard")
		(date "2025-03-12")
		(rev "1.3.4")
		(company "Antmicro Ltd")
		(comment 1 "www.antmicro.com")
		(comment 9 "footprints 32-36 of 677")
	)
	(layers
		(0 "F.Cu" signal)
		(1 "In1.Cu" signal)
		(2 "In2.Cu" signal)
		(3 "In3.Cu" signal)
		(4 "In4.Cu" jumper)
		(5 "In5.Cu" signal)
		(6 "In6.Cu" signal)
		(31 "B.Cu" signal)
		(32 "B.Adhes" user "B.Adhesive")
		(33 "F.Adhes" user "F.Adhesive")
		(34 "B.Paste" user)
		(35 "F.Paste" user)
		(36 "B.SilkS" user "B.Silkscreen")
		(37 "F.SilkS" user "F.Silkscreen")
		(38 "B.Mask" user)
		(39 "F.Mask" user)
		(40 "Dwgs.User" user "User.Drawings")
		(41 "Cmts.User" user "User.Comments")
		(42 "Eco1.User" user "User.Eco1")
		(43 "Eco2.User" user "User.Eco2")
		(44 "Edge.Cuts" user)
		(45 "Margin" user)
		(46 "B.CrtYd" user "B.Courtyard")
		(47 "F.CrtYd" user "F.Courtyard")
		(48 "B.Fab" user)
		(49 "F.Fab" user)
	)
	(footprint "antmicro-footprints:C_0402_1005Metric"
		(layer "F.Cu")
		(at 111.8 111.75 90)
		(descr "Capacitor SMD 0402")
		(tags "capacitor SMD 0402")
		(property "Reference" "C71"
			(at 0.8 0.5 90)
			(layer "F.SilkS")
			(effects
				(font
					(size 0.7 0.7)
					(thickness 0.15)
				)
				(justify left bottom)
			)
		)
		(property "Value" "C_100n_0402"
			(at 0 1.4 90)
			(layer "F.Fab")
			(effects
				(font
					(size 0.7 0.7)
					(thickness 0.15)
				)
				(justify left bottom)
			)
		)
		(property "Footprint" "antmicro-footprints:C_0402_1005Metric"
			(at 0 0 90)
			(layer "F.Fab")
			(hide yes)
			(effects
				(font
					(size 1.27 1.27)
					(thickness 0.15)
				)
			)
		)
		(property "Datasheet" "https://www.murata.com/products/productdetail?partno=GRM155R61H104KE14%23"
			(at 0 0 90)
			(layer "F.Fab")
			(hide yes)
			(effects
				(font
					(size 1.27 1.27)
					(thickness 0.15)
				)
			)
		)
		(property "Author" "Antmicro"
			(at 223.55 -0.05 0)
			(layer "F.Fab")
			(hide yes)
			(effects
				(font
					(size 1 1)
					(thickness 0.15)
				)
			)
		)
		(property "Dielectric" "X5R"
			(at 223.55 -0.05 0)
			(layer "F.Fab")
			(hide yes)
			(effects
				(font
					(size 1 1)
					(thickness 0.15)
				)
			)
		)
		(property "License" "Apache-2.0"
			(at 223.55 -0.05 0)
			(layer "F.Fab")
			(hide yes)
			(effects
				(font
					(size 1 1)
					(thickness 0.15)
				)
			)
		)
		(property "MPN" "GRM155R61H104KE14D"
			(at 223.55 -0.05 0)
			(layer "F.Fab")
			(hide yes)
			(effects
				(font
					(size 1 1)
					(thickness 0.15)
				)
			)
		)
		(property "Manufacturer" "Murata"
			(at 223.55 -0.05 0)
			(layer "F.Fab")
			(hide yes)
			(effects
				(font
					(size 1 1)
					(thickness 0.15)
				)
			)
		)
		(property "Val" "100n"
			(at 223.55 -0.05 0)
			(layer "F.Fab")
			(hide yes)
			(effects
				(font
					(size 1 1)
					(thickness 0.15)
				)
			)
		)
		(property "Voltage" "50V"
			(at 223.55 -0.05 0)
			(layer "F.Fab")
			(hide yes)
			(effects
				(font
					(size 1 1)
					(thickness 0.15)
				)
			)
		)
		(sheetname "USB3")
		(sheetfile "usb3.kicad_sch")
		(attr smd)
		(fp_rect
			(start -0.925 -0.47)
			(end 0.925 0.47)
			(stroke
				(width 0.05)
				(type default)
			)
			(fill none)
			(layer "F.CrtYd")
		)
		(fp_line
			(start 0.504 -0.25)
			(end 0.504 0.248)
			(stroke
				(width 0.15)
				(type solid)
			)
			(layer "F.Fab")
		)
		(fp_line
			(start -0.494 -0.25)
			(end 0.504 -0.25)
			(stroke
				(width 0.15)
				(type solid)
			)
			(layer "F.Fab")
		)
		(fp_line
			(start 0.504 0.248)
			(end -0.494 0.248)
			(stroke
				(width 0.15)
				(type solid)
			)
			(layer "F.Fab")
		)
		(fp_line
			(start -0.494 0.248)
			(end -0.494 -0.25)
			(stroke
				(width 0.15)
				(type solid)
			)
			(layer "F.Fab")
		)
		(fp_text user "License: Apache-2.0"
			(at -0.932 5.17 90)
			(layer "F.Fab")
			(hide yes)
			(effects
				(font
					(size 0.7 0.7)
					(thickness 0.15)
				)
				(justify left bottom)
			)
		)
		(fp_text user "Author: Antmicro"
			(at -0.932 4.17 90)
			(layer "F.Fab")
			(hide yes)
			(effects
				(font
					(size 0.7 0.7)
					(thickness 0.15)
				)
				(justify left bottom)
			)
		)
		(fp_text user "${REFERENCE}"
			(at -0.932 3.168 90)
			(layer "F.Fab")
			(hide yes)
			(effects
				(font
					(size 0.7 0.7)
					(thickness 0.15)
				)
				(justify left bottom)
			)
		)
		(pad "1" smd roundrect
			(at -0.48 0 90)
			(size 0.59 0.64)
			(layers "F.Cu" "F.Paste" "F.Mask")
			(roundrect_rratio 0.25)
			(net 267 "/USB3/USBC1_CONN_TX1_P")
			(pintype "passive")
		)
		(pad "2" smd roundrect
			(at 0.48 0 90)
			(size 0.59 0.64)
			(layers "F.Cu" "F.Paste" "F.Mask")
			(roundrect_rratio 0.25)
			(net 266 "/USB3/USBC1_TX1_P")
			(pintype "passive")
		)
	)
	(footprint "antmicro-footprints:SOD-523"
		(layer "F.Cu")
		(at 87.7 119.5 180)
		(property "Reference" "D38"
			(at 3.05 -0.43 180)
			(layer "F.SilkS")
			(effects
				(font
					(size 0.7 0.7)
					(thickness 0.15)
				)
				(justify left bottom)
			)
		)
		(property "Value" "RB521S30T1G"
			(at 0 1.499 180)
			(layer "F.Fab")
			(effects
				(font
					(size 0.7 0.7)
					(thickness 0.15)
				)
				(justify left bottom)
			)
		)
		(property "Footprint" "antmicro-footprints:SOD-523"
			(at 0 0 180)
			(layer "F.Fab")
			(hide yes)
			(effects
				(font
					(size 1.27 1.27)
					(thickness 0.15)
				)
			)
		)
		(property "Datasheet" "https://www.onsemi.com/pdf/datasheet/rb521s30t1-d.pdf"
			(at 0 0 180)
			(layer "F.Fab")
			(hide yes)
			(effects
				(font
					(size 1.27 1.27)
					(thickness 0.15)
				)
			)
		)
		(property "Author" "Antmicro"
			(at 175.4 239 0)
			(layer "F.Fab")
			(hide yes)
			(effects
				(font
					(size 1 1)
					(thickness 0.15)
				)
			)
		)
		(property "License" "Apache-2.0"
			(at 175.4 239 0)
			(layer "F.Fab")
			(hide yes)
			(effects
				(font
					(size 1 1)
					(thickness 0.15)
				)
			)
		)
		(property "MPN" "RB521S30T1G"
			(at 175.4 239 0)
			(layer "F.Fab")
			(hide yes)
			(effects
				(font
					(size 1 1)
					(thickness 0.15)
				)
			)
		)
		(property "Manufacturer" "ON Semiconductor"
			(at 175.4 239 0)
			(layer "F.Fab")
			(hide yes)
			(effects
				(font
					(size 1 1)
					(thickness 0.15)
				)
			)
		)
		(sheetname "HDMI")
		(sheetfile "hdmi.kicad_sch")
		(attr smd)
		(fp_line
			(start -0.35 -0.5)
			(end -0.35 0.5)
			(stroke
				(width 0.15)
				(type solid)
			)
			(layer "F.SilkS")
		)
		(fp_rect
			(start -1 -0.6)
			(end 1 0.6)
			(stroke
				(width 0.05)
				(type solid)
			)
			(fill none)
			(layer "F.CrtYd")
		)
		(fp_line
			(start 0.65 -0.425)
			(end 0.65 0.423)
			(stroke
				(width 0.15)
				(type solid)
			)
			(layer "F.Fab")
		)
		(fp_line
			(start -0.35 -0.4)
			(end -0.35 0.4)
			(stroke
				(width 0.15)
				(type solid)
			)
			(layer "F.Fab")
		)
		(fp_line
			(start -0.652 0.423)
			(end 0.65 0.423)
			(stroke
				(width 0.15)
				(type solid)
			)
			(layer "F.Fab")
		)
		(fp_line
			(start -0.652 0.423)
			(end -0.652 -0.425)
			(stroke
				(width 0.15)
				(type solid)
			)
			(layer "F.Fab")
		)
		(fp_line
			(start -0.652 -0.425)
			(end 0.65 -0.425)
			(stroke
				(width 0.15)
				(type solid)
			)
			(layer "F.Fab")
		)
		(fp_text user "${REFERENCE}"
			(at -1.276 3.499 180)
			(layer "F.Fab")
			(hide yes)
			(effects
				(font
					(size 0.7 0.7)
					(thickness 0.15)
				)
				(justify left bottom)
			)
		)
		(fp_text user "Author: Antmicro"
			(at -1.276 4.7 180)
			(layer "F.Fab")
			(hide yes)
			(effects
				(font
					(size 0.7 0.7)
					(thickness 0.15)
				)
				(justify left bottom)
			)
		)
		(fp_text user "License: Apache-2.0"
			(at -1.276 5.9 180)
			(layer "F.Fab")
			(hide yes)
			(effects
				(font
					(size 0.7 0.7)
					(thickness 0.15)
				)
				(justify left bottom)
			)
		)
		(pad "1" smd roundrect
			(at -0.701 0 180)
			(size 0.5 0.6)
			(layers "F.Cu" "F.Paste" "F.Mask")
			(roundrect_rratio 0.25)
			(net 498 "/HDMI/5V_HDMI")
			(pinfunction "C")
			(pintype "passive")
		)
		(pad "2" smd roundrect
			(at 0.699 0 180)
			(size 0.5 0.6)
			(layers "F.Cu" "F.Paste" "F.Mask")
			(roundrect_rratio 0.25)
			(net 424 "Net-(D38-A)")
			(pinfunction "A")
			(pintype "passive")
		)
	)
	(footprint "antmicro-footprints:R_0402_1005Metric"
		(layer "F.Cu")
		(at 148 111.5 180)
		(descr "Resistor SMD 0402")
		(tags "resistor SMD 0402")
		(property "Reference" "R336"
			(at 1.22 -5.85 180)
			(layer "F.SilkS")
			(effects
				(font
					(size 0.7 0.7)
					(thickness 0.15)
				)
				(justify left bottom)
			)
		)
		(property "Value" "R_470R_0402"
			(at 0 1.4 180)
			(layer "F.Fab")
			(effects
				(font
					(size 0.7 0.7)
					(thickness 0.15)
				)
				(justify left bottom)
			)
		)
		(property "Footprint" "antmicro-footprints:R_0402_1005Metric"
			(at 0 0 180)
			(layer "F.Fab")
			(hide yes)
			(effects
				(font
					(size 1.27 1.27)
					(thickness 0.15)
				)
			)
		)
		(property "Datasheet" "https://www.bourns.com/docs/product-datasheets/cr.pdf"
			(at 0 0 180)
			(layer "F.Fab")
			(hide yes)
			(effects
				(font
					(size 1.27 1.27)
					(thickness 0.15)
				)
			)
		)
		(property "Author" "Antmicro"
			(at 296 223 0)
			(layer "F.Fab")
			(hide yes)
			(effects
				(font
					(size 1 1)
					(thickness 0.15)
				)
			)
		)
		(property "License" "Apache-2.0"
			(at 296 223 0)
			(layer "F.Fab")
			(hide yes)
			(effects
				(font
					(size 1 1)
					(thickness 0.15)
				)
			)
		)
		(property "MPN" "CR0402-FX-4700GLF"
			(at 296 223 0)
			(layer "F.Fab")
			(hide yes)
			(effects
				(font
					(size 1 1)
					(thickness 0.15)
				)
			)
		)
		(property "Manufacturer" "Bourns"
			(at 296 223 0)
			(layer "F.Fab")
			(hide yes)
			(effects
				(font
					(size 1 1)
					(thickness 0.15)
				)
			)
		)
		(property "Tolerance" "1%"
			(at 296 223 0)
			(layer "F.Fab")
			(hide yes)
			(effects
				(font
					(size 1 1)
					(thickness 0.15)
				)
			)
		)
		(property "Val" "470R"
			(at 296 223 0)
			(layer "F.Fab")
			(hide yes)
			(effects
				(font
					(size 1 1)
					(thickness 0.15)
				)
			)
		)
		(sheetname "Peripherals")
		(sheetfile "peripherals.kicad_sch")
		(attr smd)
		(fp_rect
			(start -0.925 -0.47)
			(end 0.925 0.47)
			(stroke
				(width 0.05)
				(type default)
			)
			(fill none)
			(layer "F.CrtYd")
		)
		(fp_rect
			(start -0.5 -0.25)
			(end 0.5 0.25)
			(stroke
				(width 0.15)
				(type solid)
			)
			(fill none)
			(layer "F.Fab")
		)
		(fp_text user "Author: Antmicro"
			(at -0.95 4.169 180)
			(layer "F.Fab")
			(hide yes)
			(effects
				(font
					(size 0.7 0.7)
					(thickness 0.15)
				)
				(justify left bottom)
			)
		)
		(fp_text user "License: Apache-2.0"
			(at -0.95 5.169 180)
			(layer "F.Fab")
			(hide yes)
			(effects
				(font
					(size 0.7 0.7)
					(thickness 0.15)
				)
				(justify left bottom)
			)
		)
		(fp_text user "${REFERENCE}"
			(at -0.95 3.168 180)
			(layer "F.Fab")
			(hide yes)
			(effects
				(font
					(size 0.7 0.7)
					(thickness 0.15)
				)
				(justify left bottom)
			)
		)
		(pad "1" smd roundrect
			(at -0.48 0 180)
			(size 0.59 0.64)
			(layers "F.Cu" "F.Paste" "F.Mask")
			(roundrect_rratio 0.25)
			(net 101 "CAN_TX")
			(pintype "passive")
		)
		(pad "2" smd roundrect
			(at 0.48 0 180)
			(size 0.59 0.64)
			(layers "F.Cu" "F.Paste" "F.Mask")
			(roundrect_rratio 0.25)
			(net 601 "Net-(J11-Pad70)")
			(pintype "passive")
		)
	)
	(footprint "antmicro-footprints:R_Array_4x0402"
		(layer "F.Cu")
		(at 147.85 99.4 -90)
		(property "Reference" "R100"
			(at 1.42 -1.65 -90)
			(layer "F.SilkS")
			(effects
				(font
					(size 0.7 0.7)
					(thickness 0.15)
				)
				(justify left bottom)
			)
		)
		(property "Value" "R_4x330R_0402_array"
			(at -1.5 2 -90)
			(layer "F.Fab")
			(effects
				(font
					(size 0.7 0.7)
					(thickness 0.15)
				)
				(justify left bottom)
			)
		)
		(property "Footprint" "antmicro-footprints:R_Array_4x0402"
			(at 0 0 -90)
			(layer "F.Fab")
			(hide yes)
			(effects
				(font
					(size 1.27 1.27)
					(thickness 0.15)
				)
			)
		)
		(property "Datasheet" "http://industrial.panasonic.com/cdbs/www-data/pdf/AOC0000/AOC0000C14.pdf"
			(at 0 0 -90)
			(layer "F.Fab")
			(hide yes)
			(effects
				(font
					(size 1.27 1.27)
					(thickness 0.15)
				)
			)
		)
		(property "Author" "Antmicro"
			(at 48.45 247.25 0)
			(layer "F.Fab")
			(hide yes)
			(effects
				(font
					(size 1 1)
					(thickness 0.15)
				)
			)
		)
		(property "License" "Apache-2.0"
			(at 48.45 247.25 0)
			(layer "F.Fab")
			(hide yes)
			(effects
				(font
					(size 1 1)
					(thickness 0.15)
				)
			)
		)
		(property "MPN" "EXB-28V331JX"
			(at 48.45 247.25 0)
			(layer "F.Fab")
			(hide yes)
			(effects
				(font
					(size 1 1)
					(thickness 0.15)
				)
			)
		)
		(property "Manufacturer" "Panasonic"
			(at 48.45 247.25 0)
			(layer "F.Fab")
			(hide yes)
			(effects
				(font
					(size 1 1)
					(thickness 0.15)
				)
			)
		)
		(property "Val" "R_4x330R_0402"
			(at 48.45 247.25 0)
			(layer "F.Fab")
			(hide yes)
			(effects
				(font
					(size 1 1)
					(thickness 0.15)
				)
			)
		)
		(sheetname "Peripherals")
		(sheetfile "peripherals.kicad_sch")
		(attr smd)
		(fp_line
			(start 1.167 0.498)
			(end 1.167 -0.5)
			(stroke
				(width 0.15)
				(type solid)
			)
			(layer "F.SilkS")
		)
		(fp_line
			(start -1.17 -0.5)
			(end -1.17 0.498)
			(stroke
				(width 0.15)
				(type solid)
			)
			(layer "F.SilkS")
		)
		(fp_rect
			(start -1.2 -0.9)
			(end 1.2 0.9)
			(stroke
				(width 0.05)
				(type solid)
			)
			(fill none)
			(layer "F.CrtYd")
		)
		(fp_line
			(start -1 0.498)
			(end -1 -0.5)
			(stroke
				(width 0.15)
				(type solid)
			)
			(layer "F.Fab")
		)
		(fp_line
			(start 0.998 0.498)
			(end -1 0.498)
			(stroke
				(width 0.15)
				(type solid)
			)
			(layer "F.Fab")
		)
		(fp_line
			(start -1 -0.5)
			(end 0.998 -0.5)
			(stroke
				(width 0.15)
				(type solid)
			)
			(layer "F.Fab")
		)
		(fp_line
			(start 0.998 -0.5)
			(end 0.998 0.498)
			(stroke
				(width 0.15)
				(type solid)
			)
			(layer "F.Fab")
		)
		(fp_text user "Author: Antmicro"
			(at -1.5 4.5 -90)
			(layer "F.Fab")
			(hide yes)
			(effects
				(font
					(size 0.7 0.7)
					(thickness 0.15)
				)
				(justify left bottom)
			)
		)
		(fp_text user "License: Apache-2.0"
			(at -1.5 5.75 -90)
			(layer "F.Fab")
			(hide yes)
			(effects
				(font
					(size 0.7 0.7)
					(thickness 0.15)
				)
				(justify left bottom)
			)
		)
		(fp_text user "${REFERENCE}"
			(at -1.5 3.25 -90)
			(layer "F.Fab")
			(hide yes)
			(effects
				(font
					(size 0.7 0.7)
					(thickness 0.15)
				)
				(justify left bottom)
			)
		)
		(pad "1" smd roundrect
			(at -0.802 0.45 270)
			(size 0.4 0.5)
			(layers "F.Cu" "F.Paste" "F.Mask")
			(roundrect_rratio 0.25)
			(net 581 "/Peripherals/GPIO12_CONN")
			(pinfunction "R1.1")
			(pintype "passive")
		)
		(pad "2" smd roundrect
			(at -0.272 0.45 270)
			(size 0.4 0.5)
			(layers "F.Cu" "F.Paste" "F.Mask")
			(roundrect_rratio 0.25)
			(net 583 "/Peripherals/GPIO11_CONN")
			(pinfunction "R2.1")
			(pintype "passive")
		)
		(pad "3" smd roundrect
			(at 0.27 0.45 270)
			(size 0.4 0.5)
			(layers "F.Cu" "F.Paste" "F.Mask")
			(roundrect_rratio 0.25)
			(net 582 "/Peripherals/UART1_TXD_CONN")
			(pinfunction "R3.1")
			(pintype "passive")
		)
		(pad "4" smd roundrect
			(at 0.8 0.45 270)
			(size 0.4 0.5)
			(layers "F.Cu" "F.Paste" "F.Mask")
			(roundrect_rratio 0.25)
			(net 586 "/Peripherals/I2S0_SCLK_CONN")
			(pinfunction "R4.1")
			(pintype "passive")
		)
		(pad "5" smd roundrect
			(at 0.8 -0.452 270)
			(size 0.4 0.5)
			(layers "F.Cu" "F.Paste" "F.Mask")
			(roundrect_rratio 0.25)
			(net 75 "I2S0_SCLK")
			(pinfunction "R4.2")
			(pintype "passive")
		)
		(pad "6" smd roundrect
			(at 0.27 -0.452 270)
			(size 0.4 0.5)
			(layers "F.Cu" "F.Paste" "F.Mask")
			(roundrect_rratio 0.25)
			(net 460 "UART1_TXD")
			(pinfunction "R3.2")
			(pintype "passive")
		)
		(pad "7" smd roundrect
			(at -0.272 -0.452 270)
			(size 0.4 0.5)
			(layers "F.Cu" "F.Paste" "F.Mask")
			(roundrect_rratio 0.25)
			(net 82 "GPIO11")
			(pinfunction "R2.2")
			(pintype "passive")
		)
		(pad "8" smd roundrect
			(at -0.802 -0.452 270)
			(size 0.4 0.5)
			(layers "F.Cu" "F.Paste" "F.Mask")
			(roundrect_rratio 0.25)
			(net 83 "GPIO12")
			(pinfunction "R1.2")
			(pintype "passive")
		)
	)
	(footprint "antmicro-footprints:C_0402_1005Metric"
		(layer "F.Cu")
		(at 65.75 95.82 -90)
		(descr "Capacitor SMD 0402")
		(tags "capacitor SMD 0402")
		(property "Reference" "C102"
			(at -1.01 -1.33 90)
			(layer "F.SilkS")
			(effects
				(font
					(size 0.7 0.7)
					(thickness 0.15)
				)
				(justify right bottom)
			)
		)
		(property "Value" "C_100n_0402"
			(at -1.022927 2.155213 90)
			(layer "F.Fab")
			(effects
				(font
					(size 0.7 0.7)
					(thickness 0.15)
				)
				(justify right bottom)
			)
		)
		(property "Footprint" "antmicro-footprints:C_0402_1005Metric"
			(at 0 0 -90)
			(layer "F.Fab")
			(hide yes)
			(effects
				(font
					(size 1.27 1.27)
					(thickness 0.15)
				)
			)
		)
		(property "Datasheet" "https://www.murata.com/products/productdetail?partno=GRM155R61H104KE14%23"
			(at 0 0 -90)
			(layer "F.Fab")
			(hide yes)
			(effects
				(font
					(size 1.27 1.27)
					(thickness 0.15)
				)
			)
		)
		(property "Author" "Antmicro"
			(at -30.07 161.57 0)
			(layer "F.Fab")
			(hide yes)
			(effects
				(font
					(size 1 1)
					(thickness 0.15)
				)
			)
		)
		(property "Dielectric" "X5R"
			(at -30.07 161.57 0)
			(layer "F.Fab")
			(hide yes)
			(effects
				(font
					(size 1 1)
					(thickness 0.15)
				)
			)
		)
		(property "License" "Apache-2.0"
			(at -30.07 161.57 0)
			(layer "F.Fab")
			(hide yes)
			(effects
				(font
					(size 1 1)
					(thickness 0.15)
				)
			)
		)
		(property "MPN" "GRM155R61H104KE14D"
			(at -30.07 161.57 0)
			(layer "F.Fab")
			(hide yes)
			(effects
				(font
					(size 1 1)
					(thickness 0.15)
				)
			)
		)
		(property "Manufacturer" "Murata"
			(at -30.07 161.57 0)
			(layer "F.Fab")
			(hide yes)
			(effects
				(font
					(size 1 1)
					(thickness 0.15)
				)
			)
		)
		(property "Val" "100n"
			(at -30.07 161.57 0)
			(layer "F.Fab")
			(hide yes)
			(effects
				(font
					(size 1 1)
					(thickness 0.15)
				)
			)
		)
		(property "Voltage" "50V"
			(at -30.07 161.57 0)
			(layer "F.Fab")
			(hide yes)
			(effects
				(font
					(size 1 1)
					(thickness 0.15)
				)
			)
		)
		(sheetname "Supply")
		(sheetfile "supply.kicad_sch")
		(attr smd)
		(fp_rect
			(start -0.925 -0.47)
			(end 0.925 0.47)
			(stroke
				(width 0.05)
				(type default)
			)
			(fill none)
			(layer "F.CrtYd")
		)
		(fp_line
			(start -0.494 0.248)
			(end -0.494 -0.25)
			(stroke
				(width 0.15)
				(type solid)
			)
			(layer "F.Fab")
		)
		(fp_line
			(start 0.504 0.248)
			(end -0.494 0.248)
			(stroke
				(width 0.15)
				(type solid)
			)
			(layer "F.Fab")
		)
		(fp_line
			(start -0.494 -0.25)
			(end 0.504 -0.25)
			(stroke
				(width 0.15)
				(type solid)
			)
			(layer "F.Fab")
		)
		(fp_line
			(start 0.504 -0.25)
			(end 0.504 0.248)
			(stroke
				(width 0.15)
				(type solid)
			)
			(layer "F.Fab")
		)
		(fp_text user "${REFERENCE}"
			(at -0.939 4.599 90)
			(layer "F.Fab")
			(hide yes)
			(effects
				(font
					(size 0.7 0.7)
					(thickness 0.15)
				)
				(justify right bottom)
			)
		)
		(fp_text user "Author: Antmicro"
			(at -0.939 3.399 90)
			(layer "F.Fab")
			(hide yes)
			(effects
				(font
					(size 0.7 0.7)
					(thickness 0.15)
				)
				(justify right bottom)
			)
		)
		(fp_text user "License: Apache-2.0"
			(at -0.939 5.799 90)
			(layer "F.Fab")
			(hide yes)
			(effects
				(font
					(size 0.7 0.7)
					(thickness 0.15)
				)
				(justify right bottom)
			)
		)
		(pad "1" smd roundrect
			(at -0.48 0 270)
			(size 0.59 0.64)
			(layers "F.Cu" "F.Paste" "F.Mask")
			(roundrect_rratio 0.25)
			(net 765 "/Supply/5V_PHASE")
			(pintype "passive")
		)
		(pad "2" smd roundrect
			(at 0.48 0 270)
			(size 0.59 0.64)
			(layers "F.Cu" "F.Paste" "F.Mask")
			(roundrect_rratio 0.25)
			(net 760 "/Supply/5V_BOOT")
			(pintype "passive")
		)
	)
)
